FILE_TYPE = CONNECTIVITY;
{Allegro Design Entry HDL 17.2-2016 S081 (4005846) 1/11/2022}
"PAGE_NUMBER" = 41;
0"NC";
1"GND\g";
2"GND\g";
3"GND\g";
4"GND\g";
5"GND\g";
6"GND\g";
%"UNIVERSAL_GND"
"1","(-3225,-575)","0","logical_power","I1";
;
CDS_LIB"logical_power"
HDL_POWER"GND";
"A"6;
%"SOCKET4677_AZIF0045P001C01CS"
"38","(1275,1950)","0","pure_quanta","I10";
;
PART_NUMBER"DGA^7000023"
PART_TYPE"SMLF"
MATERIAL"IO"
VALUE"SOCKET4677_AZIF0045-P001C01CS"
$LOCATION"U2"
CDS_LIB"pure_quanta"
NEEDS_NO_SIZE"TRUE"
CDS_LMAN_SYM_OUTLINE"-1050,2150,1050,-2100"
CDS_LOCATION"U2"
$SEC"38"
CDS_SEC"38";
"VSS198"
$PN"AK12"3;
"VSS199"
$PN"AK16"3;
"VSS200"
$PN"AK18"3;
"VSS201"
$PN"AK24"3;
"VSS202"
$PN"AK30"3;
"VSS203"
$PN"AK36"3;
"VSS204"
$PN"AK4"3;
"VSS205"
$PN"AK42"3;
"VSS206"
$PN"AK49"3;
"VSS207"
$PN"AK55"3;
"VSS208"
$PN"AK61"3;
"VSS209"
$PN"AK67"3;
"VSS210"
$PN"AK73"3;
"VSS211"
$PN"AK79"3;
"VSS212"
$PN"AK8"3;
"VSS213"
$PN"AK81"3;
"VSS214"
$PN"AK83"3;
"VSS215"
$PN"AK87"3;
"VSS216"
$PN"AK91"3;
"VSS217"
$PN"AL1"3;
"VSS218"
$PN"AL13"3;
"VSS219"
$PN"AL17"3;
"VSS220"
$PN"AL5"3;
"VSS221"
$PN"AL52"3;
"VSS222"
$PN"AL80"3;
"VSS223"
$PN"AL82"3;
"VSS224"
$PN"AL84"3;
"VSS225"
$PN"AL88"3;
"VSS226"
$PN"AL9"3;
"VSS227"
$PN"AM12"3;
"VSS228"
$PN"AM16"3;
"VSS229"
$PN"AM18"3;
"VSS230"
$PN"AM20"3;
"VSS231"
$PN"AM22"3;
"VSS232"
$PN"AM24"3;
"VSS233"
$PN"AM26"3;
"VSS234"
$PN"AM28"3;
"VSS235"
$PN"AM30"3;
"VSS236"
$PN"AM32"3;
"VSS237"
$PN"AM34"3;
"VSS238"
$PN"AM36"3;
"VSS239"
$PN"AM38"3;
"VSS240"
$PN"AM4"3;
"VSS241"
$PN"AM40"3;
"VSS242"
$PN"AM42"3;
"VSS243"
$PN"AM44"3;
"VSS244"
$PN"AM47"3;
"VSS245"
$PN"AM49"3;
"VSS246"
$PN"AM51"3;
"VSS247"
$PN"AM53"3;
"VSS248"
$PN"AM55"3;
"VSS249"
$PN"AM57"3;
"VSS250"
$PN"AM59"3;
"VSS251"
$PN"AM61"3;
"VSS252"
$PN"AM63"3;
"VSS253"
$PN"AM65"3;
"VSS254"
$PN"AM67"3;
"VSS255"
$PN"AM69"3;
"VSS256"
$PN"AM71"3;
"VSS257"
$PN"AM73"3;
"VSS258"
$PN"AM75"3;
"VSS259"
$PN"AM77"3;
"VSS260"
$PN"AM8"3;
"VSS261"
$PN"AN52"3;
"VSS262"
$PN"AN84"3;
"VSS263"
$PN"AN88"3;
"VSS264"
$PN"AP12"3;
"VSS265"
$PN"AP16"3;
"VSS266"
$PN"AP18"3;
"VSS267"
$PN"AP24"3;
"VSS268"
$PN"AP30"3;
"VSS269"
$PN"AP36"3;
"VSS270"
$PN"AP4"3;
"VSS271"
$PN"AP42"3;
"VSS272"
$PN"AP49"3;
"VSS273"
$PN"AP55"3;
"VSS274"
$PN"AP61"3;
"VSS275"
$PN"AP67"3;
"VSS276"
$PN"AP73"3;
"VSS277"
$PN"AP79"4;
"VSS278"
$PN"AP8"3;
"VSS279"
$PN"AP83"4;
"VSS280"
$PN"AP87"4;
"VSS281"
$PN"AP91"4;
"VSS282"
$PN"AR1"4;
"VSS283"
$PN"AR13"4;
"VSS284"
$PN"AR19"4;
"VSS285"
$PN"AR23"4;
"VSS286"
$PN"AR25"4;
"VSS287"
$PN"AR29"4;
"VSS288"
$PN"AR31"4;
"VSS289"
$PN"AR35"4;
"VSS290"
$PN"AR37"4;
"VSS291"
$PN"AR41"4;
"VSS292"
$PN"AR43"4;
"VSS293"
$PN"AR48"4;
"VSS294"
$PN"AR5"4;
"VSS295"
$PN"AR50"4;
"VSS296"
$PN"AR54"4;
"VSS297"
$PN"AR56"4;
"VSS298"
$PN"AR60"4;
"VSS299"
$PN"AR62"4;
"VSS300"
$PN"AR66"4;
"VSS301"
$PN"AR68"4;
"VSS302"
$PN"AR72"4;
"VSS303"
$PN"AR74"4;
"VSS304"
$PN"AR78"4;
"VSS305"
$PN"AR82"4;
"VSS306"
$PN"AR84"4;
"VSS307"
$PN"AR88"4;
"VSS308"
$PN"AR9"4;
"VSS309"
$PN"AT12"4;
"VSS310"
$PN"AT16"4;
"VSS311"
$PN"AT20"4;
"VSS312"
$PN"AT22"4;
"VSS313"
$PN"AT26"4;
"VSS314"
$PN"AT28"4;
"VSS315"
$PN"AT32"4;
"VSS316"
$PN"AT34"4;
"VSS317"
$PN"AT38"4;
"VSS318"
$PN"AT4"4;
"VSS319"
$PN"AT40"4;
"VSS320"
$PN"AT44"4;
"VSS321"
$PN"AT51"4;
"VSS322"
$PN"AT53"4;
"VSS323"
$PN"AT57"4;
"VSS324"
$PN"AT59"4;
"VSS325"
$PN"AT63"4;
"VSS326"
$PN"AT65"4;
"VSS327"
$PN"AT69"4;
"VSS328"
$PN"AT71"4;
"VSS329"
$PN"AT75"4;
"VSS330"
$PN"AT77"4;
"VSS331"
$PN"AT79"4;
"VSS332"
$PN"AT8"4;
"VSS333"
$PN"AU27"4;
"VSS334"
$PN"AU31"4;
"VSS335"
$PN"AU37"4;
"VSS336"
$PN"AU39"4;
"VSS337"
$PN"AU41"4;
"VSS338"
$PN"AU45"4;
"VSS339"
$PN"AU48"4;
"VSS340"
$PN"AU70"4;
"VSS341"
$PN"AU72"4;
"VSS342"
$PN"AU74"4;
"VSS343"
$PN"AU76"4;
"VSS344"
$PN"AU80"4;
"VSS345"
$PN"AU84"4;
"VSS346"
$PN"AU88"4;
"VSS347"
$PN"AV12"4;
"VSS348"
$PN"AV16"4;
"VSS349"
$PN"AV4"4;
"VSS350"
$PN"AV77"4;
"VSS351"
$PN"AV8"4;
"VSS352"
$PN"AV87"4;
"VSS353"
$PN"AV91"4;
"VSS354"
$PN"AW1"4;
"VSS355"
$PN"AW13"4;
"VSS359"
$PN"AW5"4;
"VSS368"
$PN"AW9"4;
%"SOCKET4677_AZIF0045P001C01CS"
"39","(4300,1950)","0","pure_quanta","I11";
;
PART_NUMBER"DGA^7000023"
PART_TYPE"SMLF"
MATERIAL"IO"
VALUE"SOCKET4677_AZIF0045-P001C01CS"
$LOCATION"U2"
CDS_LIB"pure_quanta"
NEEDS_NO_SIZE"TRUE"
CDS_LMAN_SYM_OUTLINE"-1050,2150,1050,-2100"
CDS_LOCATION"U2"
$SEC"39"
CDS_SEC"39";
"VSS38"
$PN"AA82"1;
"VSS39"
$PN"AA84"1;
"VSS40"
$PN"AA88"1;
"VSS41"
$PN"AB12"1;
"VSS42"
$PN"AB16"1;
"VSS43"
$PN"AB20"1;
"VSS44"
$PN"AB22"1;
"VSS45"
$PN"AB26"1;
"VSS46"
$PN"AB28"1;
"VSS47"
$PN"AB32"1;
"VSS48"
$PN"AB34"1;
"VSS49"
$PN"AB38"1;
"VSS50"
$PN"AB4"1;
"VSS51"
$PN"AB40"1;
"VSS52"
$PN"AB44"1;
"VSS53"
$PN"AB47"1;
"VSS54"
$PN"AB51"1;
"VSS55"
$PN"AB53"1;
"VSS56"
$PN"AB57"1;
"VSS57"
$PN"AB59"1;
"VSS58"
$PN"AB63"1;
"VSS59"
$PN"AB65"1;
"VSS60"
$PN"AB69"1;
"VSS61"
$PN"AB71"1;
"VSS62"
$PN"AB75"1;
"VSS63"
$PN"AB77"1;
"VSS64"
$PN"AB79"1;
"VSS65"
$PN"AB8"1;
"VSS66"
$PN"AB81"1;
"VSS67"
$PN"AB83"1;
"VSS68"
$PN"AB87"1;
"VSS69"
$PN"AB91"1;
"VSS70"
$PN"AC1"1;
"VSS71"
$PN"AC13"1;
"VSS72"
$PN"AC21"1;
"VSS73"
$PN"AC27"1;
"VSS74"
$PN"AC33"1;
"VSS75"
$PN"AC39"1;
"VSS76"
$PN"AC45"1;
"VSS77"
$PN"AC5"1;
"VSS78"
$PN"AC52"1;
"VSS79"
$PN"AC58"1;
"VSS80"
$PN"AC64"1;
"VSS81"
$PN"AC70"1;
"VSS82"
$PN"AC76"1;
"VSS83"
$PN"AC84"1;
"VSS84"
$PN"AC88"1;
"VSS85"
$PN"AC9"1;
"VSS86"
$PN"AD12"1;
"VSS87"
$PN"AD16"1;
"VSS88"
$PN"AD4"1;
"VSS89"
$PN"AD42"1;
"VSS90"
$PN"AD79"1;
"VSS91"
$PN"AD8"1;
"VSS92"
$PN"AD83"1;
"VSS93"
$PN"AE17"1;
"VSS94"
$PN"AE19"1;
"VSS95"
$PN"AE21"1;
"VSS96"
$PN"AE23"1;
"VSS97"
$PN"AE25"1;
"VSS98"
$PN"AE27"1;
"VSS99"
$PN"AE29"1;
"VSS100"
$PN"AE31"1;
"VSS101"
$PN"AE33"1;
"VSS102"
$PN"AE35"1;
"VSS103"
$PN"AE37"1;
"VSS104"
$PN"AE39"1;
"VSS105"
$PN"AE41"1;
"VSS106"
$PN"AE43"1;
"VSS107"
$PN"AE45"1;
"VSS108"
$PN"AE48"1;
"VSS109"
$PN"AE50"1;
"VSS110"
$PN"AE52"1;
"VSS111"
$PN"AE54"1;
"VSS112"
$PN"AE56"1;
"VSS113"
$PN"AE58"1;
"VSS114"
$PN"AE60"1;
"VSS115"
$PN"AE62"1;
"VSS116"
$PN"AE64"1;
"VSS117"
$PN"AE66"1;
"VSS118"
$PN"AE68"2;
"VSS119"
$PN"AE70"2;
"VSS120"
$PN"AE72"2;
"VSS121"
$PN"AE74"2;
"VSS122"
$PN"AE76"2;
"VSS123"
$PN"AE78"2;
"VSS124"
$PN"AE84"2;
"VSS125"
$PN"AE88"2;
"VSS126"
$PN"AF12"2;
"VSS127"
$PN"AF16"2;
"VSS128"
$PN"AF4"2;
"VSS129"
$PN"AF42"2;
"VSS130"
$PN"AF8"2;
"VSS131"
$PN"AF81"2;
"VSS132"
$PN"AF87"2;
"VSS133"
$PN"AF91"2;
"VSS134"
$PN"AG1"2;
"VSS135"
$PN"AG13"2;
"VSS136"
$PN"AG21"2;
"VSS137"
$PN"AG27"2;
"VSS138"
$PN"AG33"2;
"VSS139"
$PN"AG39"2;
"VSS140"
$PN"AG45"2;
"VSS141"
$PN"AG5"2;
"VSS142"
$PN"AG52"2;
"VSS143"
$PN"AG58"2;
"VSS144"
$PN"AG64"2;
"VSS145"
$PN"AG70"2;
"VSS146"
$PN"AG76"2;
"VSS147"
$PN"AG84"2;
"VSS148"
$PN"AG88"2;
"VSS149"
$PN"AG9"2;
"VSS150"
$PN"AH12"2;
"VSS151"
$PN"AH16"2;
"VSS152"
$PN"AH20"2;
"VSS153"
$PN"AH22"2;
"VSS154"
$PN"AH26"2;
"VSS155"
$PN"AH28"2;
"VSS156"
$PN"AH32"2;
"VSS157"
$PN"AH34"2;
"VSS158"
$PN"AH38"2;
"VSS159"
$PN"AH4"2;
"VSS160"
$PN"AH40"2;
"VSS161"
$PN"AH44"2;
"VSS162"
$PN"AH47"2;
"VSS163"
$PN"AH51"2;
"VSS164"
$PN"AH53"2;
"VSS165"
$PN"AH57"2;
"VSS166"
$PN"AH59"2;
"VSS167"
$PN"AH63"2;
"VSS168"
$PN"AH65"2;
"VSS169"
$PN"AH69"2;
"VSS170"
$PN"AH71"2;
"VSS171"
$PN"AH75"2;
"VSS172"
$PN"AH77"2;
"VSS173"
$PN"AH79"2;
"VSS174"
$PN"AH8"2;
"VSS175"
$PN"AH83"2;
"VSS176"
$PN"AJ19"2;
"VSS177"
$PN"AJ23"2;
"VSS178"
$PN"AJ25"2;
"VSS179"
$PN"AJ29"2;
"VSS180"
$PN"AJ31"2;
"VSS181"
$PN"AJ35"2;
"VSS182"
$PN"AJ37"2;
"VSS183"
$PN"AJ41"2;
"VSS184"
$PN"AJ43"2;
"VSS185"
$PN"AJ48"2;
"VSS186"
$PN"AJ50"2;
"VSS187"
$PN"AJ54"2;
"VSS188"
$PN"AJ56"2;
"VSS189"
$PN"AJ60"2;
"VSS190"
$PN"AJ62"2;
"VSS191"
$PN"AJ66"2;
"VSS192"
$PN"AJ68"2;
"VSS193"
$PN"AJ72"2;
"VSS194"
$PN"AJ74"2;
"VSS195"
$PN"AJ78"2;
"VSS196"
$PN"AJ84"2;
"VSS197"
$PN"AJ88"2;
%"UNIVERSAL_GND"
"1","(-325,-575)","0","logical_power","I3";
;
CDS_LIB"logical_power"
HDL_POWER"GND";
"A"5;
%"UNIVERSAL_GND"
"1","(-175,-575)","0","logical_power","I4";
;
CDS_LIB"logical_power"
HDL_POWER"GND";
"A"4;
%"UNIVERSAL_GND"
"1","(2725,-575)","0","logical_power","I5";
;
CDS_LIB"logical_power"
HDL_POWER"GND";
"A"3;
%"UNIVERSAL_GND"
"1","(2850,-575)","0","logical_power","I6";
;
CDS_LIB"logical_power"
HDL_POWER"GND";
"A"2;
%"UNIVERSAL_GND"
"1","(5750,-575)","0","logical_power","I8";
;
CDS_LIB"logical_power"
HDL_POWER"GND";
"A"1;
%"SOCKET4677_AZIF0045P001C01CS"
"37","(-1775,1950)","0","pure_quanta","I9";
;
PART_NUMBER"DGA^7000023"
PART_TYPE"SMLF"
MATERIAL"IO"
VALUE"SOCKET4677_AZIF0045-P001C01CS"
$LOCATION"U2"
CDS_LIB"pure_quanta"
NEEDS_NO_SIZE"TRUE"
CDS_LMAN_SYM_OUTLINE"-1050,2150,1050,-2100"
CDS_LOCATION"U2"
$SEC"37"
CDS_SEC"37";
"VSS0"
$PN"BR5"6;
"VSS356"
$PN"AW21"5;
"VSS357"
$PN"AW23"5;
"VSS358"
$PN"AW25"5;
"VSS360"
$PN"AW62"5;
"VSS361"
$PN"AW66"5;
"VSS362"
$PN"AW68"5;
"VSS363"
$PN"AW72"5;
"VSS364"
$PN"AW80"5;
"VSS365"
$PN"AW82"5;
"VSS366"
$PN"AW84"5;
"VSS367"
$PN"AW88"5;
"VSS369"
$PN"AY12"5;
"VSS370"
$PN"AY16"5;
"VSS371"
$PN"AY4"5;
"VSS372"
$PN"AY71"5;
"VSS373"
$PN"AY77"5;
"VSS374"
$PN"AY79"5;
"VSS375"
$PN"AY8"5;
"VSS376"
$PN"AY81"5;
"VSS377"
$PN"AY83"5;
"VSS393"
$PN"BA17"5;
"VSS394"
$PN"BA60"5;
"VSS395"
$PN"BA64"5;
"VSS397"
$PN"BA74"5;
"VSS398"
$PN"BA84"5;
"VSS399"
$PN"BA88"5;
"VSS400"
$PN"BB10"5;
"VSS401"
$PN"BB12"5;
"VSS402"
$PN"BB16"5;
"VSS403"
$PN"BB20"5;
"VSS404"
$PN"BB22"5;
"VSS405"
$PN"BB24"5;
"VSS406"
$PN"BB26"5;
"VSS407"
$PN"BB4"5;
"VSS408"
$PN"BB63"5;
"VSS409"
$PN"BB69"5;
"VSS410"
$PN"BB71"5;
"VSS411"
$PN"BB77"5;
"VSS412"
$PN"BB79"5;
"VSS413"
$PN"BB8"5;
"VSS414"
$PN"BB83"5;
"VSS415"
$PN"BB87"5;
"VSS416"
$PN"BB91"5;
"VSS417"
$PN"BC1"5;
"VSS418"
$PN"BC13"5;
"VSS419"
$PN"BC17"5;
"VSS420"
$PN"BC5"5;
"VSS421"
$PN"BC62"5;
"VSS422"
$PN"BC66"5;
"VSS423"
$PN"BC72"5;
"VSS424"
$PN"BC76"5;
"VSS425"
$PN"BC78"5;
"VSS426"
$PN"BC84"5;
"VSS427"
$PN"BC86"5;
"VSS428"
$PN"BC88"5;
"VSS429"
$PN"BC9"5;
"VSS430"
$PN"BD12"5;
"VSS431"
$PN"BD16"5;
"VSS432"
$PN"BD20"5;
"VSS433"
$PN"BD4"5;
"VSS434"
$PN"BD8"5;
"VSS435"
$PN"BD81"5;
"VSS437"
$PN"BD85"5;
"VSS439"
$PN"BD89"5;
"VSS440"
$PN"BE64"5;
"VSS441"
$PN"BE66"5;
"VSS442"
$PN"BE68"5;
"VSS443"
$PN"BE74"5;
"VSS444"
$PN"BE76"5;
"VSS445"
$PN"BE78"5;
"VSS446"
$PN"BE84"5;
"VSS447"
$PN"BF12"5;
"VSS448"
$PN"BF16"5;
"VSS449"
$PN"BF20"5;
"VSS450"
$PN"BF4"5;
"VSS451"
$PN"BF61"5;
"VSS452"
$PN"BF63"5;
"VSS453"
$PN"BF73"5;
"VSS454"
$PN"BF75"5;
"VSS455"
$PN"BF79"6;
"VSS456"
$PN"BF8"5;
"VSS457"
$PN"BF83"6;
"VSS458"
$PN"BG1"6;
"VSS459"
$PN"BG13"6;
"VSS460"
$PN"BG17"6;
"VSS461"
$PN"BG21"6;
"VSS462"
$PN"BG23"6;
"VSS463"
$PN"BG25"6;
"VSS464"
$PN"BG5"6;
"VSS465"
$PN"BG70"6;
"VSS466"
$PN"BG9"6;
"VSS467"
$PN"BH12"6;
"VSS468"
$PN"BH16"6;
"VSS469"
$PN"BH20"6;
"VSS470"
$PN"BH4"6;
"VSS472"
$PN"BH67"6;
"VSS473"
$PN"BH73"6;
"VSS474"
$PN"BH77"6;
"VSS475"
$PN"BH8"6;
"VSS476"
$PN"BH81"6;
"VSS477"
$PN"BH83"6;
"VSS479"
$PN"BJ62"6;
"VSS480"
$PN"BJ68"6;
"VSS481"
$PN"BJ80"6;
"VSS482"
$PN"BJ82"6;
"VSS483"
$PN"BJ84"6;
"VSS484"
$PN"BJ86"6;
"VSS485"
$PN"BJ88"6;
"VSS486"
$PN"BJ90"6;
"VSS487"
$PN"BK12"6;
"VSS488"
$PN"BK16"6;
"VSS489"
$PN"BK20"6;
"VSS490"
$PN"BK4"6;
"VSS491"
$PN"BK65"6;
"VSS492"
$PN"BK71"6;
"VSS494"
$PN"BK75"6;
"VSS495"
$PN"BK79"6;
"VSS496"
$PN"BK8"6;
"VSS497"
$PN"BL1"6;
"VSS498"
$PN"BL13"6;
"VSS499"
$PN"BL17"6;
"VSS500"
$PN"BL5"6;
"VSS501"
$PN"BL68"6;
"VSS502"
$PN"BL70"6;
"VSS503"
$PN"BL72"6;
"VSS504"
$PN"BL78"6;
"VSS505"
$PN"BL9"6;
"VSS506"
$PN"BM12"6;
"VSS507"
$PN"BM16"6;
"VSS508"
$PN"BM20"6;
"VSS509"
$PN"BM22"6;
"VSS510"
$PN"BM24"6;
"VSS511"
$PN"BM26"6;
"VSS512"
$PN"BM4"6;
"VSS513"
$PN"BM61"6;
"VSS515"
$PN"BM73"6;
"VSS516"
$PN"BM77"6;
"VSS517"
$PN"BM8"6;
"VSS518"
$PN"BN31"6;
"VSS519"
$PN"BN62"6;
"VSS520"
$PN"BN70"6;
"VSS522"
$PN"BP12"6;
"VSS523"
$PN"BP16"6;
"VSS524"
$PN"BP2"6;
"VSS525"
$PN"BP20"6;
"VSS527"
$PN"BP4"6;
"VSS528"
$PN"BP63"6;
"VSS529"
$PN"BP71"6;
"VSS530"
$PN"BP73"6;
"VSS531"
$PN"BP75"6;
"VSS532"
$PN"BP77"6;
"VSS533"
$PN"BP8"6;
"VSS535"
$PN"BR13"6;
"VSS536"
$PN"BR17"6;
"VSS538"
$PN"BR27"6;
"VSS539"
$PN"BR29"6;
"VSS540"
$PN"BR31"6;
"VSS541"
$PN"BR33"6;
"VSS572"
$PN"BR9"6;
END.
